# S9S_MB_2U (Grand Teton) — schematic netlist excerpt (pin names and nets, part order shuffled) for the footprints in the layout excerpt that follows; sources: Cadence DE-HDL packaged netlist, KiCad conversion of 03242023_DA0F0TMBIJ0_F0T_Motherboard_J_brd_V01_OCP.brd

R3720  Q_RES  0 5% CHIP  pkg 0402LF  page 233 : A = SMB_LM75_2_3V3AUX_SDA_R ; B = SMB_LM75_2_3V3AUX_SDA
PC1579  Q_CAPP  560UF 2.5V 20% OSCON  pkg THLF  page 275 : A = PVCCINFAON_CPU0 ; B = GND
C1520  Q_CAP_DIFFBUS  DIFF BUS_0.22UF 6.3V 20% X6S  pkg C0201  page 177 : \1\ = P5E_CPU1_PE3_TX_C_DN<13> ; \2\ = P5E_CPU1_PE3_TX_DN<13>

(kicad_pcb
	(version 20260206)
	(generator "pcbnew")
	(generator_version "10.0")
	(general
		(thickness 1.6)
		(legacy_teardrops no)
	)
	(paper "A4")
	(title_block
		(title "03242023_DA0F0TMBIJ0_F0T_Motherboard_J_brd_V01_OCP.brd")
		(comment 1 "Grand Teton / footprints 4079-4081 of 6105")
	)
	(layers
		(0 "F.Cu" signal "TOP")
		(4 "In1.Cu" signal "GND")
		(6 "In2.Cu" signal "IN1")
		(8 "In3.Cu" signal "GND1")
		(10 "In4.Cu" signal "IN2")
		(12 "In5.Cu" signal "GND2")
		(14 "In6.Cu" signal "IN3")
		(16 "In7.Cu" signal "GND3")
		(18 "In8.Cu" signal "VCC")
		(20 "In9.Cu" signal "VCC1")
		(22 "In10.Cu" signal "GND4")
		(24 "In11.Cu" signal "IN4")
		(26 "In12.Cu" signal "GND5")
		(28 "In13.Cu" signal "IN5")
		(30 "In14.Cu" signal "GND6")
		(32 "In15.Cu" signal "IN6")
		(34 "In16.Cu" signal "GND7")
		(2 "B.Cu" signal "BOTTOM")
		(9 "F.Adhes" user "F.Adhesive")
		(11 "B.Adhes" user "B.Adhesive")
		(13 "F.Paste" user "Package Geometry/Pastemask Top")
		(15 "B.Paste" user "Package Geometry/Pastemask Bottom")
		(5 "F.SilkS" user "Ref Des/Silkscreen Top")
		(7 "B.SilkS" user "Ref Des/Silkscreen Bottom")
		(1 "F.Mask" user "Board Geometry/Soldermask Top")
		(3 "B.Mask" user "Board Geometry/Soldermask Bottom")
		(17 "Dwgs.User" user "User.Drawings")
		(19 "Cmts.User" user "User.Comments")
		(21 "Eco1.User" user "User.Eco1")
		(23 "Eco2.User" user "User.Eco2")
		(25 "Edge.Cuts" user "Board Geometry/Outline")
		(27 "Margin" user)
		(31 "F.CrtYd" user "Package Geometry/Place Bound Top")
		(29 "B.CrtYd" user "Package Geometry/Place Bound Bottom")
		(35 "F.Fab" user "Ref Des/Assembly Top")
		(33 "B.Fab" user "Ref Des/Assembly Bottom")
	)
	(footprint ""
		(layer "F.Cu")
		(at 54.242716 -107.88269 180)
		(property "Reference" "R3720"
			(at 0 0 180)
			(layer "F.SilkS")
			(hide yes)
			(effects
				(font
					(size 1.27 1.27)
				)
			)
		)
		(property "Value" ""
			(at 0 0 180)
			(layer "F.Fab")
			(effects
				(font
					(size 1.27 1.27)
				)
			)
		)
		(duplicate_pad_numbers_are_jumpers no)
		(fp_line
			(start 0.7874 0.4064)
			(end -0.7874 0.4064)
			(stroke
				(width 0.1524)
				(type default)
			)
			(layer "F.SilkS")
		)
		(fp_line
			(start 0.7874 -0.4064)
			(end 0.7874 0.4064)
			(stroke
				(width 0.1524)
				(type default)
			)
			(layer "F.SilkS")
		)
		(fp_line
			(start -0.7874 0.4064)
			(end -0.7874 -0.4064)
			(stroke
				(width 0.1524)
				(type default)
			)
			(layer "F.SilkS")
		)
		(fp_line
			(start -0.7874 -0.4064)
			(end 0.7874 -0.4064)
			(stroke
				(width 0.1524)
				(type default)
			)
			(layer "F.SilkS")
		)
		(fp_line
			(start 0.67945 0.3048)
			(end 0.120396 0.3048)
			(stroke
				(width 0.1)
				(type default)
			)
			(layer "F.Fab")
		)
		(fp_line
			(start 0.67945 -0.3048)
			(end 0.67945 0.3048)
			(stroke
				(width 0.1)
				(type default)
			)
			(layer "F.Fab")
		)
		(fp_line
			(start 0.12065 -0.2794)
			(end 0.12065 -0.3048)
			(stroke
				(width 0.1)
				(type default)
			)
			(layer "F.Fab")
		)
		(fp_line
			(start 0.12065 -0.3048)
			(end 0.67945 -0.3048)
			(stroke
				(width 0.1)
				(type default)
			)
			(layer "F.Fab")
		)
		(fp_line
			(start 0.120396 0.3048)
			(end 0.120396 0.2794)
			(stroke
				(width 0.1)
				(type default)
			)
			(layer "F.Fab")
		)
		(fp_line
			(start 0.120396 0.2794)
			(end -0.12065 0.2794)
			(stroke
				(width 0.1)
				(type default)
			)
			(layer "F.Fab")
		)
		(fp_line
			(start -0.12065 0.3048)
			(end -0.67945 0.3048)
			(stroke
				(width 0.1)
				(type default)
			)
			(layer "F.Fab")
		)
		(fp_line
			(start -0.12065 0.2794)
			(end -0.12065 0.3048)
			(stroke
				(width 0.1)
				(type default)
			)
			(layer "F.Fab")
		)
		(fp_line
			(start -0.12065 -0.2794)
			(end 0.12065 -0.2794)
			(stroke
				(width 0.1)
				(type default)
			)
			(layer "F.Fab")
		)
		(fp_line
			(start -0.12065 -0.305054)
			(end -0.12065 -0.2794)
			(stroke
				(width 0.1)
				(type default)
			)
			(layer "F.Fab")
		)
		(fp_line
			(start -0.67945 0.3048)
			(end -0.67945 -0.305054)
			(stroke
				(width 0.1)
				(type default)
			)
			(layer "F.Fab")
		)
		(fp_line
			(start -0.67945 -0.305054)
			(end -0.12065 -0.305054)
			(stroke
				(width 0.1)
				(type default)
			)
			(layer "F.Fab")
		)
		(pad "1" smd circle
			(at -0.40005 0 180)
			(size 0 0)
			(layers "F.Cu" "F.Mask" "F.Paste")
			(net "SMB_LM75_2_3V3AUX_SDA_R")
		)
		(pad "2" smd circle
			(at 0.40005 0 180)
			(size 0 0)
			(layers "F.Cu" "F.Mask" "F.Paste")
			(net "SMB_LM75_2_3V3AUX_SDA")
		)
	)
	(footprint ""
		(layer "F.Cu")
		(at 127.602234 -408.517344 -90)
		(property "Reference" "C1520"
			(at 0 0 270)
			(layer "F.SilkS")
			(hide yes)
			(effects
				(font
					(size 1.27 1.27)
				)
			)
		)
		(property "Value" ""
			(at 0 0 270)
			(layer "F.Fab")
			(effects
				(font
					(size 1.27 1.27)
				)
			)
		)
		(duplicate_pad_numbers_are_jumpers no)
		(fp_line
			(start -0.299974 0.150114)
			(end -0.299974 -0.150114)
			(stroke
				(width 0.1)
				(type default)
			)
			(layer "F.Fab")
		)
		(fp_line
			(start 0.299974 0.150114)
			(end -0.299974 0.150114)
			(stroke
				(width 0.1)
				(type default)
			)
			(layer "F.Fab")
		)
		(fp_line
			(start -0.299974 -0.150114)
			(end 0.299974 -0.150114)
			(stroke
				(width 0.1)
				(type default)
			)
			(layer "F.Fab")
		)
		(fp_line
			(start 0.299974 -0.150114)
			(end 0.299974 0.150114)
			(stroke
				(width 0.1)
				(type default)
			)
			(layer "F.Fab")
		)
		(pad "1" smd rect
			(at -0.2667 0 270)
			(size 0.3048 0.381)
			(layers "F.Cu" "F.Mask" "F.Paste")
			(net "P5E_CPU1_PE3_TX_C_DN<13>")
		)
		(pad "2" smd rect
			(at 0.2667 0 270)
			(size 0.3048 0.381)
			(layers "F.Cu" "F.Mask" "F.Paste")
			(net "P5E_CPU1_PE3_TX_DN<13>")
		)
	)
	(footprint ""
		(layer "F.Cu")
		(at 400.558 -183.429148)
		(property "Reference" "PC1579"
			(at 0 0 0)
			(layer "F.SilkS")
			(hide yes)
			(effects
				(font
					(size 1.27 1.27)
				)
			)
		)
		(property "Value" ""
			(at 0 0 0)
			(layer "F.Fab")
			(effects
				(font
					(size 1.27 1.27)
				)
			)
		)
		(duplicate_pad_numbers_are_jumpers no)
		(fp_line
			(start 2.750058 0.999998)
			(end -2.750058 0.999998)
			(stroke
				(width 0.1524)
				(type default)
			)
			(layer "F.SilkS")
		)
		(fp_circle
			(center 0 0.999998)
			(end 2.750058 0.999998)
			(stroke
				(width 0.1524)
				(type default)
			)
			(fill no)
			(layer "F.SilkS")
		)
		(fp_poly
			(pts
				(arc
					(start 2.750058 0.999998)
					(mid 0 3.750056)
					(end -2.750058 0.999998)
				)
			)
			(stroke
				(width 0)
				(type default)
			)
			(fill yes)
			(layer "F.SilkS")
		)
		(fp_circle
			(center 0 0.999998)
			(end 2.750058 0.999998)
			(stroke
				(width 0.1)
				(type default)
			)
			(fill no)
			(layer "F.Fab")
		)
		(pad "1" thru_hole rect
			(at 0 0)
			(size 1.5748 1.5748)
			(drill 1.0668)
			(layers "*.Cu" "*.Mask")
			(remove_unused_layers no)
			(net "PVCCINFAON_CPU0")
			(clearance 0)
			(padstack
				(mode front_inner_back)
				(layer "Inner"
					(shape circle)
					(size 1.5748 1.5748)
					(clearance 0)
				)
				(layer "B.Cu"
					(shape rect)
					(size 1.5748 1.5748)
					(clearance 0)
				)
			)
		)
		(pad "2" thru_hole circle
			(at 0 1.999996)
			(size 1.5748 1.5748)
			(drill 1.0668)
			(layers "*.Cu" "*.Mask")
			(remove_unused_layers no)
			(net "GND")
			(clearance 0)
		)
	)
)
